# T6G (Grand Teton) — schematic netlist excerpt (pin names and nets, part order shuffled) for the footprints in the layout excerpt that follows; sources: Cadence DE-HDL packaged netlist, KiCad conversion of 04192023_DAF0TMB3IC0_F0TG_MB_C_brd_V02_OCP.brd

R1379  Q_RES  4.7K 5% CHIP  pkg 0201LF  page 185 : A = P1V8_CPU0_RT_1D ; B = SMB_RT_CPU0_P3_ROM_MUX_2D_R_SCL
C6551  Q_CAP_DIFFBUS  DIFF BUS_0.22UF 6.3V 20% X6S  pkg C0201  page 286 : \1\ = P5E_CPU0_P1_TX_BUF_C_DP<9> ; \2\ = P5E_CPU0_P1_TX_BUF_DP<9>
R9020  Q_RES  1K 1% EMPTY  pkg 0402LF  page 267 : A = P3V3_AUX ; B = U142_VS
C497  Q_CAP  1UF 4V 20% X6S  pkg 0201  page 356 : A = P0V9_CPU1_RT3_2A ; B = GND

(kicad_pcb
	(version 20260206)
	(generator "pcbnew")
	(generator_version "10.0")
	(general
		(thickness 1.6)
		(legacy_teardrops no)
	)
	(paper "A4")
	(title_block
		(title "04192023_DAF0TMB3IC0_F0TG_MB_C_brd_V02_OCP.brd")
		(comment 1 "Grand Teton / footprints 7962-7965 of 8354")
	)
	(layers
		(0 "F.Cu" signal "TOP")
		(4 "In1.Cu" signal "GND")
		(6 "In2.Cu" signal "IN1")
		(8 "In3.Cu" signal "GND1")
		(10 "In4.Cu" signal "IN2")
		(12 "In5.Cu" signal "GND2")
		(14 "In6.Cu" signal "IN3")
		(16 "In7.Cu" signal "GND3")
		(18 "In8.Cu" signal "VCC")
		(20 "In9.Cu" signal "VCC1")
		(22 "In10.Cu" signal "GND4")
		(24 "In11.Cu" signal "IN4")
		(26 "In12.Cu" signal "GND5")
		(28 "In13.Cu" signal "IN5")
		(30 "In14.Cu" signal "GND6")
		(32 "In15.Cu" signal "IN6")
		(34 "In16.Cu" signal "GND7")
		(2 "B.Cu" signal "BOTTOM")
		(9 "F.Adhes" user "F.Adhesive")
		(11 "B.Adhes" user "B.Adhesive")
		(13 "F.Paste" user "Package Geometry/Pastemask Top")
		(15 "B.Paste" user "Package Geometry/Pastemask Bottom")
		(5 "F.SilkS" user "Ref Des/Silkscreen Top")
		(7 "B.SilkS" user "Ref Des/Silkscreen Bottom")
		(1 "F.Mask" user "Board Geometry/Soldermask Top")
		(3 "B.Mask" user "Board Geometry/Soldermask Bottom")
		(17 "Dwgs.User" user "User.Drawings")
		(19 "Cmts.User" user "User.Comments")
		(21 "Eco1.User" user "User.Eco1")
		(23 "Eco2.User" user "User.Eco2")
		(25 "Edge.Cuts" user "Board Geometry/Outline")
		(27 "Margin" user)
		(31 "F.CrtYd" user "Package Geometry/Place Bound Top")
		(29 "B.CrtYd" user "Package Geometry/Place Bound Bottom")
		(35 "F.Fab" user "Ref Des/Assembly Top")
		(33 "B.Fab" user "Ref Des/Assembly Bottom")
	)
	(footprint ""
		(layer "B.Cu")
		(at 254.635 -336.25536 180)
		(property "Reference" "R1379"
			(at 0 0 0)
			(layer "B.SilkS")
			(hide yes)
			(effects
				(font
					(size 1.27 1.27)
				)
				(justify mirror)
			)
		)
		(property "Value" ""
			(at 0 0 0)
			(layer "B.Fab")
			(effects
				(font
					(size 1.27 1.27)
				)
				(justify mirror)
			)
		)
		(duplicate_pad_numbers_are_jumpers no)
		(fp_line
			(start 0.32512 0.175006)
			(end 0.32512 -0.175006)
			(stroke
				(width 0.1)
				(type default)
			)
			(layer "B.Fab")
		)
		(fp_line
			(start 0.32512 -0.175006)
			(end -0.32512 -0.175006)
			(stroke
				(width 0.1)
				(type default)
			)
			(layer "B.Fab")
		)
		(fp_line
			(start -0.32512 0.175006)
			(end 0.32512 0.175006)
			(stroke
				(width 0.1)
				(type default)
			)
			(layer "B.Fab")
		)
		(fp_line
			(start -0.32512 -0.175006)
			(end -0.32512 0.175006)
			(stroke
				(width 0.1)
				(type default)
			)
			(layer "B.Fab")
		)
		(pad "1" smd rect
			(at 0.2667 0)
			(size 0.3048 0.381)
			(layers "B.Cu" "B.Mask" "B.Paste")
			(net "P1V8_CPU0_RT_1D")
		)
		(pad "2" smd rect
			(at -0.2667 0 180)
			(size 0.3048 0.381)
			(layers "B.Cu" "B.Mask" "B.Paste")
			(net "SMB_RT_CPU0_P3_ROM_MUX_2D_R_SCL")
		)
	)
	(footprint ""
		(layer "B.Cu")
		(at 118.078504 -386.766562 90)
		(property "Reference" "C497"
			(at 0 0 90)
			(layer "B.SilkS")
			(hide yes)
			(effects
				(font
					(size 1.27 1.27)
				)
				(justify mirror)
			)
		)
		(property "Value" ""
			(at 0 0 90)
			(layer "B.Fab")
			(effects
				(font
					(size 1.27 1.27)
				)
				(justify mirror)
			)
		)
		(duplicate_pad_numbers_are_jumpers no)
		(fp_line
			(start 0.299974 -0.150114)
			(end -0.299974 -0.150114)
			(stroke
				(width 0.1)
				(type default)
			)
			(layer "B.Fab")
		)
		(fp_line
			(start -0.299974 -0.150114)
			(end -0.299974 0.150114)
			(stroke
				(width 0.1)
				(type default)
			)
			(layer "B.Fab")
		)
		(fp_line
			(start 0.299974 0.150114)
			(end 0.299974 -0.150114)
			(stroke
				(width 0.1)
				(type default)
			)
			(layer "B.Fab")
		)
		(fp_line
			(start -0.299974 0.150114)
			(end 0.299974 0.150114)
			(stroke
				(width 0.1)
				(type default)
			)
			(layer "B.Fab")
		)
		(pad "1" smd rect
			(at 0.2667 0 270)
			(size 0.3048 0.381)
			(layers "B.Cu" "B.Mask" "B.Paste")
			(net "P0V9_CPU1_RT3_2A")
		)
		(pad "2" smd rect
			(at -0.2667 0 270)
			(size 0.3048 0.381)
			(layers "B.Cu" "B.Mask" "B.Paste")
			(net "GND")
		)
	)
	(footprint ""
		(layer "B.Cu")
		(at 333.783686 -416.899344 90)
		(property "Reference" "C6551"
			(at 0 0 90)
			(layer "B.SilkS")
			(hide yes)
			(effects
				(font
					(size 1.27 1.27)
				)
				(justify mirror)
			)
		)
		(property "Value" ""
			(at 0 0 90)
			(layer "B.Fab")
			(effects
				(font
					(size 1.27 1.27)
				)
				(justify mirror)
			)
		)
		(duplicate_pad_numbers_are_jumpers no)
		(fp_line
			(start 0.299974 -0.150114)
			(end -0.299974 -0.150114)
			(stroke
				(width 0.1)
				(type default)
			)
			(layer "B.Fab")
		)
		(fp_line
			(start -0.299974 -0.150114)
			(end -0.299974 0.150114)
			(stroke
				(width 0.1)
				(type default)
			)
			(layer "B.Fab")
		)
		(fp_line
			(start 0.299974 0.150114)
			(end 0.299974 -0.150114)
			(stroke
				(width 0.1)
				(type default)
			)
			(layer "B.Fab")
		)
		(fp_line
			(start -0.299974 0.150114)
			(end 0.299974 0.150114)
			(stroke
				(width 0.1)
				(type default)
			)
			(layer "B.Fab")
		)
		(pad "1" smd rect
			(at 0.2667 0 270)
			(size 0.3048 0.381)
			(layers "B.Cu" "B.Mask" "B.Paste")
			(net "P5E_CPU0_P1_TX_BUF_C_DP<9>")
		)
		(pad "2" smd rect
			(at -0.2667 0 270)
			(size 0.3048 0.381)
			(layers "B.Cu" "B.Mask" "B.Paste")
			(net "P5E_CPU0_P1_TX_BUF_DP<9>")
		)
	)
	(footprint ""
		(layer "B.Cu")
		(at 181.297834 -421.37711 -90)
		(property "Reference" "R9020"
			(at 0 0 90)
			(layer "B.SilkS")
			(hide yes)
			(effects
				(font
					(size 1.27 1.27)
				)
				(justify mirror)
			)
		)
		(property "Value" ""
			(at 0 0 90)
			(layer "B.Fab")
			(effects
				(font
					(size 1.27 1.27)
				)
				(justify mirror)
			)
		)
		(duplicate_pad_numbers_are_jumpers no)
		(fp_line
			(start -0.7874 0.4064)
			(end 0.7874 0.4064)
			(stroke
				(width 0.1524)
				(type default)
			)
			(layer "B.SilkS")
		)
		(fp_line
			(start 0.7874 0.4064)
			(end 0.7874 -0.4064)
			(stroke
				(width 0.1524)
				(type default)
			)
			(layer "B.SilkS")
		)
		(fp_line
			(start -0.7874 -0.4064)
			(end -0.7874 0.4064)
			(stroke
				(width 0.1524)
				(type default)
			)
			(layer "B.SilkS")
		)
		(fp_line
			(start 0.7874 -0.4064)
			(end -0.7874 -0.4064)
			(stroke
				(width 0.1524)
				(type default)
			)
			(layer "B.SilkS")
		)
		(fp_line
			(start -0.67945 0.3048)
			(end -0.120396 0.3048)
			(stroke
				(width 0.1)
				(type default)
			)
			(layer "B.Fab")
		)
		(fp_line
			(start -0.120396 0.3048)
			(end -0.120396 0.2794)
			(stroke
				(width 0.1)
				(type default)
			)
			(layer "B.Fab")
		)
		(fp_line
			(start 0.12065 0.3048)
			(end 0.67945 0.3048)
			(stroke
				(width 0.1)
				(type default)
			)
			(layer "B.Fab")
		)
		(fp_line
			(start 0.67945 0.3048)
			(end 0.67945 -0.305054)
			(stroke
				(width 0.1)
				(type default)
			)
			(layer "B.Fab")
		)
		(fp_line
			(start -0.120396 0.2794)
			(end 0.12065 0.2794)
			(stroke
				(width 0.1)
				(type default)
			)
			(layer "B.Fab")
		)
		(fp_line
			(start 0.12065 0.2794)
			(end 0.12065 0.3048)
			(stroke
				(width 0.1)
				(type default)
			)
			(layer "B.Fab")
		)
		(fp_line
			(start -0.12065 -0.2794)
			(end -0.12065 -0.3048)
			(stroke
				(width 0.1)
				(type default)
			)
			(layer "B.Fab")
		)
		(fp_line
			(start 0.12065 -0.2794)
			(end -0.12065 -0.2794)
			(stroke
				(width 0.1)
				(type default)
			)
			(layer "B.Fab")
		)
		(fp_line
			(start -0.67945 -0.3048)
			(end -0.67945 0.3048)
			(stroke
				(width 0.1)
				(type default)
			)
			(layer "B.Fab")
		)
		(fp_line
			(start -0.12065 -0.3048)
			(end -0.67945 -0.3048)
			(stroke
				(width 0.1)
				(type default)
			)
			(layer "B.Fab")
		)
		(fp_line
			(start 0.12065 -0.305054)
			(end 0.12065 -0.2794)
			(stroke
				(width 0.1)
				(type default)
			)
			(layer "B.Fab")
		)
		(fp_line
			(start 0.67945 -0.305054)
			(end 0.12065 -0.305054)
			(stroke
				(width 0.1)
				(type default)
			)
			(layer "B.Fab")
		)
		(pad "1" smd circle
			(at 0.40005 0 90)
			(size 0 0)
			(layers "B.Cu" "B.Mask" "B.Paste")
			(net "P3V3_AUX")
		)
		(pad "2" smd circle
			(at -0.40005 0 90)
			(size 0 0)
			(layers "B.Cu" "B.Mask" "B.Paste")
			(net "U142_VS")
		)
	)
)
